(kicad_pcb
	(version 20260206)
	(generator "pcbnew")
	(generator_version "10.0")
	(general
		(thickness 1.6)
		(legacy_teardrops no)
	)
	(paper "A4")
	(title_block
		(title "timecard-production-celestica-r4006 — R4006-B0001-02_R01.brd")
		(comment 1 "Time Appliance Project (Time Card) / footprints 601-605 of 1113")
	)
	(layers
		(0 "F.Cu" signal "TOP")
		(4 "In1.Cu" signal "L02_GND1")
		(6 "In2.Cu" signal "L03_SIG1")
		(8 "In3.Cu" signal "L04_GND2")
		(10 "In4.Cu" signal "L05_VCC1")
		(12 "In5.Cu" signal "L06_VCC2")
		(14 "In6.Cu" signal "L07_GND3")
		(16 "In7.Cu" signal "L08_SIG2")
		(18 "In8.Cu" signal "L09_GND4")
		(2 "B.Cu" signal "BOTTOM")
		(9 "F.Adhes" user "F.Adhesive")
		(11 "B.Adhes" user "B.Adhesive")
		(13 "F.Paste" user "Package Geometry/Pastemask Top")
		(15 "B.Paste" user "Package Geometry/Pastemask Bottom")
		(5 "F.SilkS" user "Ref Des/Silkscreen Top")
		(7 "B.SilkS" user "Ref Des/Silkscreen Bottom")
		(1 "F.Mask" user "Board Geometry/Soldermask Top")
		(3 "B.Mask" user "Board Geometry/Soldermask Bottom")
		(17 "Dwgs.User" user "User.Drawings")
		(19 "Cmts.User" user "User.Comments")
		(21 "Eco1.User" user "User.Eco1")
		(23 "Eco2.User" user "User.Eco2")
		(25 "Edge.Cuts" user "Board Geometry/Outline")
		(27 "Margin" user)
		(31 "F.CrtYd" user "Package Geometry/Place Bound Top")
		(29 "B.CrtYd" user "Package Geometry/Place Bound Bottom")
		(35 "F.Fab" user "Ref Des/Assembly Top")
		(33 "B.Fab" user "Ref Des/Assembly Bottom")
	)
	(footprint ""
		(layer "F.Cu")
		(at 5.969 -54.356 90)
		(property "Reference" "CR4"
			(at 0.381 2.57937 90)
			(unlocked yes)
			(layer "F.SilkS")
			(effects
				(font
					(size 0.7874 0.5842)
					(thickness 0.1524)
				)
			)
		)
		(property "Value" ""
			(at 0 0 90)
			(layer "F.Fab")
			(effects
				(font
					(size 1.27 1.27)
				)
			)
		)
		(property "Device Type" "DIODE_4_V1-G122-10123-01"
			(at 0.254 2.702306 90)
			(unlocked yes)
			(layer "F.Fab")
			(hide yes)
			(effects
				(font
					(size 0.7874 0.5842)
					(thickness 0.1524)
				)
			)
		)
		(property "User Part Number" "PARTNUM*"
			(at 0.254 3.718306 90)
			(unlocked yes)
			(layer "Cmts.User")
			(hide yes)
			(effects
				(font
					(size 0.7874 0.5842)
					(thickness 0.1524)
				)
			)
		)
		(duplicate_pad_numbers_are_jumpers no)
		(fp_line
			(start 2.0828 -1.7018)
			(end 2.0828 1.7018)
			(stroke
				(width 0.1)
				(type default)
			)
			(layer "F.SilkS")
		)
		(fp_line
			(start -2.0828 -1.7018)
			(end 2.0828 -1.7018)
			(stroke
				(width 0.1)
				(type default)
			)
			(layer "F.SilkS")
		)
		(fp_line
			(start 2.0828 1.7018)
			(end -2.0828 1.7018)
			(stroke
				(width 0.1)
				(type default)
			)
			(layer "F.SilkS")
		)
		(fp_line
			(start -2.0828 1.7018)
			(end -2.0828 -1.7018)
			(stroke
				(width 0.1)
				(type default)
			)
			(layer "F.SilkS")
		)
		(fp_poly
			(pts
				(arc
					(start -2.6162 -0.508)
					(mid -2.6162 -1.27)
					(end -2.6162 -0.508)
				)
			)
			(stroke
				(width 0)
				(type default)
			)
			(fill yes)
			(layer "F.SilkS")
		)
		(fp_rect
			(start -2.3368 -1.9304)
			(end 2.3368 1.9304)
			(stroke
				(width 0)
				(type default)
			)
			(fill no)
			(layer "F.CrtYd")
		)
		(fp_line
			(start 0.6477 -1.42875)
			(end 0.6477 1.42875)
			(stroke
				(width 0.1)
				(type default)
			)
			(layer "F.Fab")
		)
		(fp_line
			(start -0.6477 -1.42875)
			(end 0.6477 -1.42875)
			(stroke
				(width 0.1)
				(type default)
			)
			(layer "F.Fab")
		)
		(fp_line
			(start 1.143 -1.1811)
			(end 1.143 -0.7239)
			(stroke
				(width 0.1)
				(type default)
			)
			(layer "F.Fab")
		)
		(fp_line
			(start 0.6477 -1.1811)
			(end 1.143 -1.1811)
			(stroke
				(width 0.1)
				(type default)
			)
			(layer "F.Fab")
		)
		(fp_line
			(start -0.6477 -1.1811)
			(end -0.6477 -0.3175)
			(stroke
				(width 0.1)
				(type default)
			)
			(layer "F.Fab")
		)
		(fp_line
			(start -1.143 -1.1811)
			(end -0.6477 -1.1811)
			(stroke
				(width 0.1)
				(type default)
			)
			(layer "F.Fab")
		)
		(fp_line
			(start 1.143 -0.7239)
			(end 0.6477 -0.7239)
			(stroke
				(width 0.1)
				(type default)
			)
			(layer "F.Fab")
		)
		(fp_line
			(start 0.6477 -0.7239)
			(end 0.6477 -1.1811)
			(stroke
				(width 0.1)
				(type default)
			)
			(layer "F.Fab")
		)
		(fp_line
			(start -0.6477 -0.3175)
			(end -1.143 -0.3175)
			(stroke
				(width 0.1)
				(type default)
			)
			(layer "F.Fab")
		)
		(fp_line
			(start -1.143 -0.3175)
			(end -1.143 -1.1811)
			(stroke
				(width 0.1)
				(type default)
			)
			(layer "F.Fab")
		)
		(fp_line
			(start 1.143 0.7239)
			(end 1.143 1.1811)
			(stroke
				(width 0.1)
				(type default)
			)
			(layer "F.Fab")
		)
		(fp_line
			(start 0.6477 0.7239)
			(end 1.143 0.7239)
			(stroke
				(width 0.1)
				(type default)
			)
			(layer "F.Fab")
		)
		(fp_line
			(start -0.6477 0.7239)
			(end -0.6477 1.1811)
			(stroke
				(width 0.1)
				(type default)
			)
			(layer "F.Fab")
		)
		(fp_line
			(start -1.143 0.7239)
			(end -0.6477 0.7239)
			(stroke
				(width 0.1)
				(type default)
			)
			(layer "F.Fab")
		)
		(fp_line
			(start 1.143 1.1811)
			(end 0.6477 1.1811)
			(stroke
				(width 0.1)
				(type default)
			)
			(layer "F.Fab")
		)
		(fp_line
			(start 0.6477 1.1811)
			(end 0.6477 0.7239)
			(stroke
				(width 0.1)
				(type default)
			)
			(layer "F.Fab")
		)
		(fp_line
			(start -0.6477 1.1811)
			(end -1.143 1.1811)
			(stroke
				(width 0.1)
				(type default)
			)
			(layer "F.Fab")
		)
		(fp_line
			(start -1.143 1.1811)
			(end -1.143 0.7239)
			(stroke
				(width 0.1)
				(type default)
			)
			(layer "F.Fab")
		)
		(fp_line
			(start 0.6477 1.42875)
			(end -0.6477 1.42875)
			(stroke
				(width 0.1)
				(type default)
			)
			(layer "F.Fab")
		)
		(fp_line
			(start -0.6477 1.42875)
			(end -0.6477 -1.42875)
			(stroke
				(width 0.1)
				(type default)
			)
			(layer "F.Fab")
		)
		(fp_poly
			(pts
				(arc
					(start -0.381 -0.5588)
					(mid -0.381 -0.9398)
					(end -0.381 -0.5588)
				)
			)
			(stroke
				(width 0)
				(type default)
			)
			(fill yes)
			(layer "F.Fab")
		)
		(fp_text user "4"
			(at 1.36525 -2.3622 0)
			(unlocked yes)
			(layer "F.SilkS")
			(effects
				(font
					(size 0.635 0.4064)
					(thickness 0.1524)
				)
				(justify left)
			)
		)
		(fp_text user "2"
			(at -2.57175 2.0828 0)
			(unlocked yes)
			(layer "F.SilkS")
			(effects
				(font
					(size 0.635 0.4064)
					(thickness 0.1524)
				)
				(justify left)
			)
		)
		(fp_text user "3"
			(at 1.92405 2.1209 0)
			(unlocked yes)
			(layer "F.SilkS")
			(effects
				(font
					(size 0.635 0.4064)
					(thickness 0.1524)
				)
				(justify left)
			)
		)
		(fp_text user "4"
			(at 1.668526 -1.822704 0)
			(unlocked yes)
			(layer "F.Fab")
			(effects
				(font
					(size 0.7874 0.5842)
					(thickness 0.1524)
				)
				(justify left)
			)
		)
		(fp_text user "2"
			(at -1.887474 0.844296 0)
			(unlocked yes)
			(layer "F.Fab")
			(effects
				(font
					(size 0.7874 0.5842)
					(thickness 0.1524)
				)
				(justify left)
			)
		)
		(fp_text user "3"
			(at 1.287526 1.479296 0)
			(unlocked yes)
			(layer "F.Fab")
			(effects
				(font
					(size 0.7874 0.5842)
					(thickness 0.1524)
				)
				(justify left)
			)
		)
		(pad "1" smd rect
			(at -1.1049 -0.7493 90)
			(size 1.4478 1.0922)
			(layers "F.Cu" "F.Mask" "F.Paste")
			(net "SG")
		)
		(pad "2" smd rect
			(at -1.1049 0.9525 90)
			(size 1.4478 0.9906)
			(layers "F.Cu" "F.Mask" "F.Paste")
			(net "SMA2_SIG_IO_CONN")
		)
		(pad "3" smd rect
			(at 1.1049 0.9525 90)
			(size 1.4478 0.9906)
			(layers "F.Cu" "F.Mask" "F.Paste")
			(net "SMA1_SIG_IO_CONN")
		)
		(pad "4" smd rect
			(at 1.1049 -0.9525 90)
			(size 1.4478 0.9906)
			(layers "F.Cu" "F.Mask" "F.Paste")
			(net "Net_567")
		)
		(zone
			(layer "F.Cu")
			(hatch none 0.5)
			(connect_pads
				(clearance 0)
			)
			(min_thickness 0.25)
			(keepout
				(tracks allowed)
				(vias not_allowed)
				(pads allowed)
				(copperpour not_allowed)
				(footprints allowed)
			)
			(placement
				(enabled no)
				(sheetname "")
			)
			(fill
				(thermal_gap 0.5)
				(thermal_bridge_width 0.5)
				(island_removal_mode 0)
			)
			(polygon
				(pts
					(xy 4.6736 -53.7083) (xy 4.5339 -53.7083) (xy 4.5339 -54.737) (xy 5.5118 -54.737) (xy 5.5118 -55.0037)
					(xy 6.4262 -55.0037) (xy 6.4262 -54.737) (xy 7.4041 -54.737) (xy 7.4041 -53.975) (xy 6.4262 -53.975)
					(xy 6.4262 -53.7083) (xy 5.7658 -53.7083) (xy 5.7658 -53.975) (xy 4.6736 -53.975)
				)
			)
		)
	)
	(footprint ""
		(layer "F.Cu")
		(at 13.462 -66.167 -90)
		(property "Reference" "R120"
			(at -4.953 0.59563 90)
			(unlocked yes)
			(layer "F.SilkS")
			(effects
				(font
					(size 0.7874 0.5842)
					(thickness 0.1524)
				)
			)
		)
		(property "Value" "VAL*"
			(at 0.02032 2.13233 270)
			(unlocked yes)
			(layer "F.Fab")
			(hide yes)
			(effects
				(font
					(size 0.7874 0.5842)
					(thickness 0.1524)
				)
			)
		)
		(property "Tolerance" "TOL*"
			(at 0.044704 3.05435 270)
			(unlocked yes)
			(layer "Cmts.User")
			(hide yes)
			(effects
				(font
					(size 0.7874 0.5842)
					(thickness 0.1524)
				)
			)
		)
		(property "User Part Number" "PARTNUM*"
			(at 0.02032 4.024884 270)
			(unlocked yes)
			(layer "Cmts.User")
			(hide yes)
			(effects
				(font
					(size 0.7874 0.5842)
					(thickness 0.1524)
				)
			)
		)
		(property "Device Type" "RESISTOR-G155-11000-01,100OHM,A"
			(at 0.008382 1.210564 270)
			(unlocked yes)
			(layer "F.Fab")
			(hide yes)
			(effects
				(font
					(size 0.7874 0.5842)
					(thickness 0.1524)
				)
			)
		)
		(duplicate_pad_numbers_are_jumpers no)
		(fp_line
			(start -1.143 0.5588)
			(end 1.143 0.5588)
			(stroke
				(width 0.1)
				(type default)
			)
			(layer "F.SilkS")
		)
		(fp_line
			(start 1.143 0.5588)
			(end 1.143 -0.5588)
			(stroke
				(width 0.1)
				(type default)
			)
			(layer "F.SilkS")
		)
		(fp_line
			(start -1.143 -0.5588)
			(end -1.143 0.5588)
			(stroke
				(width 0.1)
				(type default)
			)
			(layer "F.SilkS")
		)
		(fp_line
			(start 1.143 -0.5588)
			(end -1.143 -0.5588)
			(stroke
				(width 0.1)
				(type default)
			)
			(layer "F.SilkS")
		)
		(fp_poly
			(pts
				(xy -1.143 0.5588) (xy 1.143 0.5588) (xy 1.143 -0.5588) (xy -1.143 -0.5588)
			)
			(stroke
				(width 0)
				(type default)
			)
			(fill no)
			(layer "F.CrtYd")
		)
		(fp_line
			(start -0.508 0.3048)
			(end 0.508 0.3048)
			(stroke
				(width 0.1)
				(type default)
			)
			(layer "F.Fab")
		)
		(fp_line
			(start 0.508 0.3048)
			(end 0.508 -0.3048)
			(stroke
				(width 0.1)
				(type default)
			)
			(layer "F.Fab")
		)
		(fp_line
			(start -0.508 -0.3048)
			(end -0.508 0.3048)
			(stroke
				(width 0.1)
				(type default)
			)
			(layer "F.Fab")
		)
		(fp_line
			(start 0.508 -0.3048)
			(end -0.508 -0.3048)
			(stroke
				(width 0.1)
				(type default)
			)
			(layer "F.Fab")
		)
		(pad "1" smd rect
			(at -0.5334 0 270)
			(size 0.7112 0.6096)
			(layers "F.Cu" "F.Mask" "F.Paste")
			(net "ANT1_OUT")
		)
		(pad "2" smd rect
			(at 0.5334 0 270)
			(size 0.7112 0.6096)
			(layers "F.Cu" "F.Mask" "F.Paste")
			(net "UNNAMED_12_74HCT2G125DPTSSOP8_6")
		)
		(zone
			(layer "F.Cu")
			(hatch none 0.5)
			(connect_pads
				(clearance 0)
			)
			(min_thickness 0.25)
			(keepout
				(tracks allowed)
				(vias not_allowed)
				(pads allowed)
				(copperpour not_allowed)
				(footprints allowed)
			)
			(placement
				(enabled no)
				(sheetname "")
			)
			(fill
				(thermal_gap 0.5)
				(thermal_bridge_width 0.5)
				(island_removal_mode 0)
			)
			(polygon
				(pts
					(xy 13.1572 -66.2432) (xy 13.1572 -66.0908) (xy 13.7668 -66.0908) (xy 13.7668 -66.2432)
				)
			)
		)
		(zone
			(layer "F.Cu")
			(hatch none 0.5)
			(connect_pads
				(clearance 0)
			)
			(min_thickness 0.25)
			(keepout
				(tracks not_allowed)
				(vias allowed)
				(pads allowed)
				(copperpour not_allowed)
				(footprints allowed)
			)
			(placement
				(enabled no)
				(sheetname "")
			)
			(fill
				(thermal_gap 0.5)
				(thermal_bridge_width 0.5)
				(island_removal_mode 0)
			)
			(polygon
				(pts
					(xy 13.1572 -66.2432) (xy 13.1572 -66.0908) (xy 13.7668 -66.0908) (xy 13.7668 -66.2432)
				)
			)
		)
	)
	(footprint ""
		(layer "F.Cu")
		(at 135.4074 -57.3786 -90)
		(property "Reference" "C255"
			(at -0.4064 2.14503 90)
			(unlocked yes)
			(layer "F.SilkS")
			(effects
				(font
					(size 0.7874 0.5842)
					(thickness 0.1524)
				)
			)
		)
		(property "Value" "VAL*"
			(at 0.0762 2.067306 270)
			(unlocked yes)
			(layer "F.Fab")
			(hide yes)
			(effects
				(font
					(size 0.7874 0.5842)
					(thickness 0.1524)
				)
			)
		)
		(property "Device Type" "CAPACITOR-G105-0B104-EK,0.1UF,A"
			(at 0.0508 1.127506 270)
			(unlocked yes)
			(layer "F.Fab")
			(hide yes)
			(effects
				(font
					(size 0.7874 0.5842)
					(thickness 0.1524)
				)
			)
		)
		(property "User Part Number" "PARTNUM*"
			(at 0.1016 4.023106 270)
			(unlocked yes)
			(layer "Cmts.User")
			(hide yes)
			(effects
				(font
					(size 0.7874 0.5842)
					(thickness 0.1524)
				)
			)
		)
		(property "Tolerance" "TOL*"
			(at 0.0762 3.032506 270)
			(unlocked yes)
			(layer "Cmts.User")
			(hide yes)
			(effects
				(font
					(size 0.7874 0.5842)
					(thickness 0.1524)
				)
			)
		)
		(duplicate_pad_numbers_are_jumpers no)
		(fp_line
			(start -1.143 0.5588)
			(end 1.143 0.5588)
			(stroke
				(width 0.1)
				(type default)
			)
			(layer "F.SilkS")
		)
		(fp_line
			(start 1.143 0.5588)
			(end 1.143 -0.5588)
			(stroke
				(width 0.1)
				(type default)
			)
			(layer "F.SilkS")
		)
		(fp_line
			(start -1.143 -0.5588)
			(end -1.143 0.5588)
			(stroke
				(width 0.1)
				(type default)
			)
			(layer "F.SilkS")
		)
		(fp_line
			(start 1.143 -0.5588)
			(end -1.143 -0.5588)
			(stroke
				(width 0.1)
				(type default)
			)
			(layer "F.SilkS")
		)
		(fp_rect
			(start -1.143 -0.5588)
			(end 1.143 0.5588)
			(stroke
				(width 0)
				(type default)
			)
			(fill no)
			(layer "F.CrtYd")
		)
		(fp_line
			(start -0.508 0.3048)
			(end 0.508 0.3048)
			(stroke
				(width 0.1)
				(type default)
			)
			(layer "F.Fab")
		)
		(fp_line
			(start 0.508 0.3048)
			(end 0.508 -0.3048)
			(stroke
				(width 0.1)
				(type default)
			)
			(layer "F.Fab")
		)
		(fp_line
			(start -0.508 -0.3048)
			(end -0.508 0.3048)
			(stroke
				(width 0.1)
				(type default)
			)
			(layer "F.Fab")
		)
		(fp_line
			(start 0.508 -0.3048)
			(end -0.508 -0.3048)
			(stroke
				(width 0.1)
				(type default)
			)
			(layer "F.Fab")
		)
		(pad "1" smd rect
			(at -0.5334 0 270)
			(size 0.7112 0.6096)
			(layers "F.Cu" "F.Mask" "F.Paste")
			(net "XP12R0V")
		)
		(pad "2" smd rect
			(at 0.5334 0 270)
			(size 0.7112 0.6096)
			(layers "F.Cu" "F.Mask" "F.Paste")
			(net "SG")
		)
		(zone
			(layer "F.Cu")
			(hatch none 0.5)
			(connect_pads
				(clearance 0)
			)
			(min_thickness 0.25)
			(keepout
				(tracks allowed)
				(vias not_allowed)
				(pads allowed)
				(copperpour not_allowed)
				(footprints allowed)
			)
			(placement
				(enabled no)
				(sheetname "")
			)
			(fill
				(thermal_gap 0.5)
				(thermal_bridge_width 0.5)
				(island_removal_mode 0)
			)
			(polygon
				(pts
					(xy 135.7122 -57.4548) (xy 135.1026 -57.4548) (xy 135.1026 -57.3024) (xy 135.7122 -57.3024)
				)
			)
		)
	)
	(footprint ""
		(layer "F.Cu")
		(at 119.6848 -29.3878 90)
		(property "Reference" "TP203"
			(at -4.1656 1.12395 90)
			(unlocked yes)
			(layer "F.SilkS")
			(effects
				(font
					(size 0.635 0.4064)
					(thickness 0.1524)
				)
				(justify left)
			)
		)
		(property "Value" ""
			(at 0 0 90)
			(layer "F.Fab")
			(effects
				(font
					(size 1.27 1.27)
				)
			)
		)
		(property "Device Type" "TP_PIONT-TP010CT020B030_PTH-TPA"
			(at -1.341882 0.996696 90)
			(unlocked yes)
			(layer "F.Fab")
			(hide yes)
			(effects
				(font
					(size 0.7874 0.5842)
					(thickness 0.1524)
				)
				(justify left)
			)
		)
		(duplicate_pad_numbers_are_jumpers no)
		(fp_poly
			(pts
				(arc
					(start 0 0.889)
					(mid 0 -0.889)
					(end 0 0.889)
				)
			)
			(stroke
				(width 0)
				(type default)
			)
			(fill no)
			(layer "B.CrtYd")
		)
		(fp_poly
			(pts
				(arc
					(start 0 0.889)
					(mid 0 -0.889)
					(end 0 0.889)
				)
			)
			(stroke
				(width 0)
				(type default)
			)
			(fill no)
			(layer "F.CrtYd")
		)
		(pad "1" thru_hole circle
			(at 0 0 90)
			(size 0.508 0.508)
			(drill 0.254)
			(layers "*.Cu" "*.Mask")
			(remove_unused_layers no)
			(net "IO_L24P_35")
			(clearance 0.1016)
			(padstack
				(mode front_inner_back)
				(layer "Inner"
					(shape circle)
					(size 0.508 0.508)
					(clearance 0.1016)
				)
				(layer "B.Cu"
					(shape circle)
					(size 0.762 0.762)
					(clearance -0.0254)
				)
			)
		)
	)
	(footprint ""
		(layer "F.Cu")
		(at 89.9922 -101.2698)
		(property "Reference" "C49"
			(at 3.048 0.16637 0)
			(unlocked yes)
			(layer "F.SilkS")
			(effects
				(font
					(size 0.7874 0.5842)
					(thickness 0.1524)
				)
			)
		)
		(property "Value" "VAL*"
			(at 0.0762 2.067306 0)
			(unlocked yes)
			(layer "F.Fab")
			(hide yes)
			(effects
				(font
					(size 0.7874 0.5842)
					(thickness 0.1524)
				)
			)
		)
		(property "Tolerance" "TOL*"
			(at 0.0762 3.032506 0)
			(unlocked yes)
			(layer "Cmts.User")
			(hide yes)
			(effects
				(font
					(size 0.7874 0.5842)
					(thickness 0.1524)
				)
			)
		)
		(property "User Part Number" "PARTNUM*"
			(at 0.1016 4.023106 0)
			(unlocked yes)
			(layer "Cmts.User")
			(hide yes)
			(effects
				(font
					(size 0.7874 0.5842)
					(thickness 0.1524)
				)
			)
		)
		(property "Device Type" "CAPACITOR-G105-0B223-EK,0.022UA"
			(at 0.0508 1.127506 0)
			(unlocked yes)
			(layer "F.Fab")
			(hide yes)
			(effects
				(font
					(size 0.7874 0.5842)
					(thickness 0.1524)
				)
			)
		)
		(duplicate_pad_numbers_are_jumpers no)
		(fp_line
			(start -1.143 -0.5588)
			(end -1.143 0.5588)
			(stroke
				(width 0.1)
				(type default)
			)
			(layer "F.SilkS")
		)
		(fp_line
			(start -1.143 0.5588)
			(end 1.143 0.5588)
			(stroke
				(width 0.1)
				(type default)
			)
			(layer "F.SilkS")
		)
		(fp_line
			(start 1.143 -0.5588)
			(end -1.143 -0.5588)
			(stroke
				(width 0.1)
				(type default)
			)
			(layer "F.SilkS")
		)
		(fp_line
			(start 1.143 0.5588)
			(end 1.143 -0.5588)
			(stroke
				(width 0.1)
				(type default)
			)
			(layer "F.SilkS")
		)
		(fp_rect
			(start -1.143 0.5588)
			(end 1.143 -0.5588)
			(stroke
				(width 0)
				(type default)
			)
			(fill no)
			(layer "F.CrtYd")
		)
		(fp_line
			(start -0.508 -0.3048)
			(end -0.508 0.3048)
			(stroke
				(width 0.1)
				(type default)
			)
			(layer "F.Fab")
		)
		(fp_line
			(start -0.508 0.3048)
			(end 0.508 0.3048)
			(stroke
				(width 0.1)
				(type default)
			)
			(layer "F.Fab")
		)
		(fp_line
			(start 0.508 -0.3048)
			(end -0.508 -0.3048)
			(stroke
				(width 0.1)
				(type default)
			)
			(layer "F.Fab")
		)
		(fp_line
			(start 0.508 0.3048)
			(end 0.508 -0.3048)
			(stroke
				(width 0.1)
				(type default)
			)
			(layer "F.Fab")
		)
		(pad "1" smd rect
			(at -0.5334 0)
			(size 0.7112 0.6096)
			(layers "F.Cu" "F.Mask" "F.Paste")
			(net "XP3R3V_SS")
		)
		(pad "2" smd rect
			(at 0.5334 0)
			(size 0.7112 0.6096)
			(layers "F.Cu" "F.Mask" "F.Paste")
			(net "XP3R3V_AGND")
		)
		(zone
			(layer "F.Cu")
			(hatch none 0.5)
			(connect_pads
				(clearance 0)
			)
			(min_thickness 0.25)
			(keepout
				(tracks allowed)
				(vias not_allowed)
				(pads allowed)
				(copperpour not_allowed)
				(footprints allowed)
			)
			(placement
				(enabled no)
				(sheetname "")
			)
			(fill
				(thermal_gap 0.5)
				(thermal_bridge_width 0.5)
				(island_removal_mode 0)
			)
			(polygon
				(pts
					(xy 89.916 -100.965) (xy 90.0684 -100.965) (xy 90.0684 -101.5746) (xy 89.916 -101.5746)
				)
			)
		)
	)
)
